(kicad_pcb
	(version 20241229)
	(generator "pcbnew")
	(generator_version "9.0")
	(general
		(thickness 1.6296)
		(legacy_teardrops no)
	)
	(paper "A3")
	(title_block
		(title "Thunderbolt to 10GbE adapter")
		(date "2026-04-21")
		(rev "1.1.0")
		(company "Antmicro Ltd")
		(comment 1 "www.antmicro.com")
		(comment 9 "footprints 374-378 of 703")
	)
	(layers
		(0 "F.Cu" signal)
		(4 "In1.Cu" signal)
		(6 "In2.Cu" signal)
		(8 "In3.Cu" signal)
		(10 "In4.Cu" signal)
		(12 "In5.Cu" signal)
		(14 "In6.Cu" signal)
		(2 "B.Cu" signal)
		(9 "F.Adhes" user "F.Adhesive")
		(11 "B.Adhes" user "B.Adhesive")
		(13 "F.Paste" user)
		(15 "B.Paste" user)
		(5 "F.SilkS" user "F.Silkscreen")
		(7 "B.SilkS" user "B.Silkscreen")
		(1 "F.Mask" user)
		(3 "B.Mask" user)
		(17 "Dwgs.User" user "User.Drawings")
		(19 "Cmts.User" user "User.Comments")
		(21 "Eco1.User" user "User.Eco1")
		(23 "Eco2.User" user "User.Eco2")
		(25 "Edge.Cuts" user)
		(27 "Margin" user)
		(31 "F.CrtYd" user "F.Courtyard")
		(29 "B.CrtYd" user "B.Courtyard")
		(35 "F.Fab" user)
		(33 "B.Fab" user)
	)
	(footprint "antmicro-footprints:C_0402_1005Metric"
		(layer "F.Cu")
		(at 165.265 64 -90)
		(descr "Capacitor SMD 0402")
		(tags "capacitor SMD 0402")
		(property "Reference" "C283"
			(at -5 0.065 270)
			(layer "F.SilkS")
			(effects
				(font
					(size 0.7 0.7)
					(thickness 0.15)
				)
				(justify left bottom)
			)
		)
		(property "Value" "C_100n_0402"
			(at -1.022927 2.155213 270)
			(layer "F.Fab")
			(effects
				(font
					(size 0.7 0.7)
					(thickness 0.15)
				)
				(justify left bottom)
			)
		)
		(property "Datasheet" "https://www.murata.com/products/productdetail?partno=GRM155R61H104KE14%23"
			(at 0 0 270)
			(layer "F.Fab")
			(hide yes)
			(effects
				(font
					(size 1.27 1.27)
					(thickness 0.15)
				)
			)
		)
		(property "Description" "SMD Multilayer Ceramic Capacitor, 0.1 µF, 50 V, 0402 [1005 Metric], ± 10%, X5R, GRM Series"
			(at 0 0 270)
			(layer "F.Fab")
			(hide yes)
			(effects
				(font
					(size 1.27 1.27)
					(thickness 0.15)
				)
			)
		)
		(property "MPN" "GRM155R61H104KE14D"
			(at 0 0 270)
			(unlocked yes)
			(layer "F.Fab")
			(hide yes)
			(effects
				(font
					(size 1 1)
					(thickness 0.15)
				)
			)
		)
		(property "Val" "100n"
			(at 0 0 270)
			(unlocked yes)
			(layer "F.Fab")
			(hide yes)
			(effects
				(font
					(size 1 1)
					(thickness 0.15)
				)
			)
		)
		(property "Voltage" "50V"
			(at 0 0 270)
			(unlocked yes)
			(layer "F.Fab")
			(hide yes)
			(effects
				(font
					(size 1 1)
					(thickness 0.15)
				)
			)
		)
		(property "Dielectric" "X5R"
			(at 0 0 270)
			(unlocked yes)
			(layer "F.Fab")
			(hide yes)
			(effects
				(font
					(size 1 1)
					(thickness 0.15)
				)
			)
		)
		(property "Manufacturer" "Murata"
			(at 0 0 270)
			(unlocked yes)
			(layer "F.Fab")
			(hide yes)
			(effects
				(font
					(size 1 1)
					(thickness 0.15)
				)
			)
		)
		(property "License" "Apache-2.0"
			(at 0 0 270)
			(unlocked yes)
			(layer "F.Fab")
			(hide yes)
			(effects
				(font
					(size 1 1)
					(thickness 0.15)
				)
			)
		)
		(property "Author" "Antmicro"
			(at 0 0 270)
			(unlocked yes)
			(layer "F.Fab")
			(hide yes)
			(effects
				(font
					(size 1 1)
					(thickness 0.15)
				)
			)
		)
		(sheetname "/X710-AT2 10GbE/")
		(sheetfile "x710-at2-10gbe.kicad_sch")
		(attr smd)
		(fp_rect
			(start -0.925 -0.47)
			(end 0.925 0.47)
			(stroke
				(width 0.05)
				(type default)
			)
			(fill no)
			(layer "F.CrtYd")
		)
		(fp_line
			(start -0.494 0.248)
			(end -0.494 -0.25)
			(stroke
				(width 0.15)
				(type solid)
			)
			(layer "F.Fab")
		)
		(fp_line
			(start 0.504 0.248)
			(end -0.494 0.248)
			(stroke
				(width 0.15)
				(type solid)
			)
			(layer "F.Fab")
		)
		(fp_line
			(start -0.494 -0.25)
			(end 0.504 -0.25)
			(stroke
				(width 0.15)
				(type solid)
			)
			(layer "F.Fab")
		)
		(fp_line
			(start 0.504 -0.25)
			(end 0.504 0.248)
			(stroke
				(width 0.15)
				(type solid)
			)
			(layer "F.Fab")
		)
		(fp_text user "License: Apache-2.0"
			(at -0.939 5.799 270)
			(layer "F.Fab")
			(effects
				(font
					(size 0.7 0.7)
					(thickness 0.15)
				)
				(justify left bottom)
			)
		)
		(fp_text user "Author: Antmicro"
			(at -0.939 3.399 270)
			(layer "F.Fab")
			(effects
				(font
					(size 0.7 0.7)
					(thickness 0.15)
				)
				(justify left bottom)
			)
		)
		(fp_text user "${REFERENCE}"
			(at -0.939 4.599 270)
			(layer "F.Fab")
			(effects
				(font
					(size 0.7 0.7)
					(thickness 0.15)
				)
				(justify left bottom)
			)
		)
		(pad "1" smd roundrect
			(at -0.48 0 270)
			(size 0.59 0.64)
			(layers "F.Cu" "F.Mask" "F.Paste")
			(roundrect_rratio 0.25)
			(net 23 "GND")
			(pintype "passive")
		)
		(pad "2" smd roundrect
			(at 0.48 0 270)
			(size 0.59 0.64)
			(layers "F.Cu" "F.Mask" "F.Paste")
			(roundrect_rratio 0.25)
			(net 56 "/X710-AT2 10GbE/3V3_OSC")
			(pintype "passive")
		)
	)
	(footprint "antmicro-footprints:R_0402_1005Metric"
		(layer "F.Cu")
		(at 134 86.25 90)
		(descr "Resistor SMD 0402")
		(tags "resistor SMD 0402")
		(property "Reference" "R71"
			(at -1.8 -4.2 90)
			(layer "F.SilkS")
			(effects
				(font
					(size 0.7 0.7)
					(thickness 0.15)
				)
				(justify left bottom)
			)
		)
		(property "Value" "R_10k_0402"
			(at -1.011843 1.772047 90)
			(layer "F.Fab")
			(effects
				(font
					(size 0.7 0.7)
					(thickness 0.15)
				)
				(justify left bottom)
			)
		)
		(property "Datasheet" "https://www.bourns.com/docs/product-datasheets/cr.pdf"
			(at 0 0 90)
			(layer "F.Fab")
			(hide yes)
			(effects
				(font
					(size 1.27 1.27)
					(thickness 0.15)
				)
			)
		)
		(property "Description" "SMD Chip Resistor, 10 kohm, ± 1%, 62.5 mW, 0402 [1005 Metric], Thick Film, General Purpose"
			(at 0 0 90)
			(layer "F.Fab")
			(hide yes)
			(effects
				(font
					(size 1.27 1.27)
					(thickness 0.15)
				)
			)
		)
		(property "MPN" "CR0402-FX-1002GLF"
			(at 0 0 90)
			(unlocked yes)
			(layer "F.Fab")
			(hide yes)
			(effects
				(font
					(size 1 1)
					(thickness 0.15)
				)
			)
		)
		(property "Manufacturer" "Bourns"
			(at 0 0 90)
			(unlocked yes)
			(layer "F.Fab")
			(hide yes)
			(effects
				(font
					(size 1 1)
					(thickness 0.15)
				)
			)
		)
		(property "License" "Apache-2.0"
			(at 0 0 90)
			(unlocked yes)
			(layer "F.Fab")
			(hide yes)
			(effects
				(font
					(size 1 1)
					(thickness 0.15)
				)
			)
		)
		(property "Author" "Antmicro"
			(at 0 0 90)
			(unlocked yes)
			(layer "F.Fab")
			(hide yes)
			(effects
				(font
					(size 1 1)
					(thickness 0.15)
				)
			)
		)
		(property "Val" "10k"
			(at 0 0 90)
			(unlocked yes)
			(layer "F.Fab")
			(hide yes)
			(effects
				(font
					(size 1 1)
					(thickness 0.15)
				)
			)
		)
		(property "Tolerance" "1%"
			(at 0 0 90)
			(unlocked yes)
			(layer "F.Fab")
			(hide yes)
			(effects
				(font
					(size 1 1)
					(thickness 0.15)
				)
			)
		)
		(sheetname "/TB Controller/")
		(sheetfile "tb.kicad_sch")
		(attr smd)
		(fp_rect
			(start -0.925 -0.47)
			(end 0.925 0.47)
			(stroke
				(width 0.05)
				(type default)
			)
			(fill no)
			(layer "F.CrtYd")
		)
		(fp_rect
			(start -0.5 -0.25)
			(end 0.5 0.25)
			(stroke
				(width 0.15)
				(type solid)
			)
			(fill no)
			(layer "F.Fab")
		)
		(fp_text user "Author: Antmicro"
			(at -0.95 4.169 90)
			(layer "F.Fab")
			(effects
				(font
					(size 0.7 0.7)
					(thickness 0.15)
				)
				(justify left bottom)
			)
		)
		(fp_text user "${REFERENCE}"
			(at -0.95 3.168 90)
			(layer "F.Fab")
			(effects
				(font
					(size 0.7 0.7)
					(thickness 0.15)
				)
				(justify left bottom)
			)
		)
		(fp_text user "License: Apache-2.0"
			(at -0.95 5.169 90)
			(layer "F.Fab")
			(effects
				(font
					(size 0.7 0.7)
					(thickness 0.15)
				)
				(justify left bottom)
			)
		)
		(pad "1" smd roundrect
			(at -0.48 0 90)
			(size 0.59 0.64)
			(layers "F.Cu" "F.Mask" "F.Paste")
			(roundrect_rratio 0.25)
			(net 23 "GND")
			(pintype "passive")
		)
		(pad "2" smd roundrect
			(at 0.48 0 90)
			(size 0.59 0.64)
			(layers "F.Cu" "F.Mask" "F.Paste")
			(roundrect_rratio 0.25)
			(net 392 "/TB Controller/~{PE_RST}")
			(pintype "passive")
		)
	)
	(footprint "antmicro-footprints:R_0402_1005Metric"
		(layer "F.Cu")
		(at 117 66.495 180)
		(descr "Resistor SMD 0402")
		(tags "resistor SMD 0402")
		(property "Reference" "R133"
			(at -3 -1.4 180)
			(layer "F.SilkS")
			(effects
				(font
					(size 0.7 0.7)
					(thickness 0.15)
				)
				(justify left bottom)
			)
		)
		(property "Value" "R_1k_0402"
			(at -1.011843 1.772047 180)
			(layer "F.Fab")
			(effects
				(font
					(size 0.7 0.7)
					(thickness 0.15)
				)
				(justify left bottom)
			)
		)
		(property "Datasheet" "https://www.bourns.com/docs/product-datasheets/cr.pdf"
			(at 0 0 180)
			(layer "F.Fab")
			(hide yes)
			(effects
				(font
					(size 1.27 1.27)
					(thickness 0.15)
				)
			)
		)
		(property "Description" "SMD Chip Resistor, 1 kohm, ± 1%, 63 mW, 0402 [1005 Metric], Thick Film, General Purpose"
			(at 0 0 180)
			(layer "F.Fab")
			(hide yes)
			(effects
				(font
					(size 1.27 1.27)
					(thickness 0.15)
				)
			)
		)
		(property "MPN" "CR0402-FX-1001GLF"
			(at 0 0 180)
			(unlocked yes)
			(layer "F.Fab")
			(hide yes)
			(effects
				(font
					(size 1 1)
					(thickness 0.15)
				)
			)
		)
		(property "Manufacturer" "Bourns"
			(at 0 0 180)
			(unlocked yes)
			(layer "F.Fab")
			(hide yes)
			(effects
				(font
					(size 1 1)
					(thickness 0.15)
				)
			)
		)
		(property "License" "Apache-2.0"
			(at 0 0 180)
			(unlocked yes)
			(layer "F.Fab")
			(hide yes)
			(effects
				(font
					(size 1 1)
					(thickness 0.15)
				)
			)
		)
		(property "Author" "Antmicro"
			(at 0 0 180)
			(unlocked yes)
			(layer "F.Fab")
			(hide yes)
			(effects
				(font
					(size 1 1)
					(thickness 0.15)
				)
			)
		)
		(property "Val" "1k"
			(at 0 0 180)
			(unlocked yes)
			(layer "F.Fab")
			(hide yes)
			(effects
				(font
					(size 1 1)
					(thickness 0.15)
				)
			)
		)
		(property "Tolerance" "1%"
			(at 0 0 180)
			(unlocked yes)
			(layer "F.Fab")
			(hide yes)
			(effects
				(font
					(size 1 1)
					(thickness 0.15)
				)
			)
		)
		(sheetname "/X710-AT2 RSVD/")
		(sheetfile "x710-at2-rsvd.kicad_sch")
		(attr smd)
		(fp_rect
			(start -0.925 -0.47)
			(end 0.925 0.47)
			(stroke
				(width 0.05)
				(type default)
			)
			(fill no)
			(layer "F.CrtYd")
		)
		(fp_rect
			(start -0.5 -0.25)
			(end 0.5 0.25)
			(stroke
				(width 0.15)
				(type solid)
			)
			(fill no)
			(layer "F.Fab")
		)
		(fp_text user "${REFERENCE}"
			(at -0.95 3.168 180)
			(layer "F.Fab")
			(effects
				(font
					(size 0.7 0.7)
					(thickness 0.15)
				)
				(justify left bottom)
			)
		)
		(fp_text user "License: Apache-2.0"
			(at -0.95 5.169 180)
			(layer "F.Fab")
			(effects
				(font
					(size 0.7 0.7)
					(thickness 0.15)
				)
				(justify left bottom)
			)
		)
		(fp_text user "Author: Antmicro"
			(at -0.95 4.169 180)
			(layer "F.Fab")
			(effects
				(font
					(size 0.7 0.7)
					(thickness 0.15)
				)
				(justify left bottom)
			)
		)
		(pad "1" smd roundrect
			(at -0.48 0 180)
			(size 0.59 0.64)
			(layers "F.Cu" "F.Mask" "F.Paste")
			(roundrect_rratio 0.25)
			(net 90 "/X710-AT2 RSVD/DEBUG_W7")
			(pintype "passive")
		)
		(pad "2" smd roundrect
			(at 0.48 0 180)
			(size 0.59 0.64)
			(layers "F.Cu" "F.Mask" "F.Paste")
			(roundrect_rratio 0.25)
			(net 86 "/X710-AT2 RSVD/DEBUG_EN")
			(pintype "passive")
		)
	)
	(footprint "antmicro-footprints:R_0402_1005Metric"
		(layer "B.Cu")
		(at 154.58 146.66 90)
		(descr "Resistor SMD 0402")
		(tags "resistor SMD 0402")
		(property "Reference" "R210"
			(at -1.09 0.42 270)
			(layer "B.SilkS")
			(effects
				(font
					(size 0.7 0.7)
					(thickness 0.15)
				)
				(justify left bottom mirror)
			)
		)
		(property "Value" "R_220R_0402"
			(at -1.011843 -1.772047 270)
			(layer "B.Fab")
			(effects
				(font
					(size 0.7 0.7)
					(thickness 0.15)
				)
				(justify left bottom mirror)
			)
		)
		(property "Datasheet" "https://www.bourns.com/docs/product-datasheets/cr.pdf"
			(at 0 0 270)
			(layer "B.Fab")
			(hide yes)
			(effects
				(font
					(size 1.27 1.27)
					(thickness 0.15)
				)
				(justify mirror)
			)
		)
		(property "Description" "SMD Chip Resistor, 220 ohm, ± 1%, 62.5 mW, 0402 [1005 Metric], Thick Film, General Purpose"
			(at 0 0 270)
			(layer "B.Fab")
			(hide yes)
			(effects
				(font
					(size 1.27 1.27)
					(thickness 0.15)
				)
				(justify mirror)
			)
		)
		(property "MPN" "CR0402-FX-2200GLF"
			(at 0 0 90)
			(unlocked yes)
			(layer "B.Fab")
			(hide yes)
			(effects
				(font
					(size 1 1)
					(thickness 0.15)
				)
				(justify mirror)
			)
		)
		(property "Manufacturer" "Bourns"
			(at 0 0 90)
			(unlocked yes)
			(layer "B.Fab")
			(hide yes)
			(effects
				(font
					(size 1 1)
					(thickness 0.15)
				)
				(justify mirror)
			)
		)
		(property "License" "Apache-2.0"
			(at 0 0 90)
			(unlocked yes)
			(layer "B.Fab")
			(hide yes)
			(effects
				(font
					(size 1 1)
					(thickness 0.15)
				)
				(justify mirror)
			)
		)
		(property "Author" "Antmicro"
			(at 0 0 90)
			(unlocked yes)
			(layer "B.Fab")
			(hide yes)
			(effects
				(font
					(size 1 1)
					(thickness 0.15)
				)
				(justify mirror)
			)
		)
		(property "Val" "220R"
			(at 0 0 90)
			(unlocked yes)
			(layer "B.Fab")
			(hide yes)
			(effects
				(font
					(size 1 1)
					(thickness 0.15)
				)
				(justify mirror)
			)
		)
		(property "Tolerance" "1%"
			(at 0 0 90)
			(unlocked yes)
			(layer "B.Fab")
			(hide yes)
			(effects
				(font
					(size 1 1)
					(thickness 0.15)
				)
				(justify mirror)
			)
		)
		(sheetname "/2xRJ45/")
		(sheetfile "2xrj45.kicad_sch")
		(attr smd)
		(fp_rect
			(start -0.925 0.47)
			(end 0.925 -0.47)
			(stroke
				(width 0.05)
				(type default)
			)
			(fill no)
			(layer "B.CrtYd")
		)
		(fp_rect
			(start -0.5 0.25)
			(end 0.5 -0.25)
			(stroke
				(width 0.15)
				(type solid)
			)
			(fill no)
			(layer "B.Fab")
		)
		(fp_text user "License: Apache-2.0"
			(at -0.95 -5.169 270)
			(layer "B.Fab")
			(effects
				(font
					(size 0.7 0.7)
					(thickness 0.15)
				)
				(justify left bottom mirror)
			)
		)
		(fp_text user "${REFERENCE}"
			(at -0.95 -3.168 270)
			(layer "B.Fab")
			(effects
				(font
					(size 0.7 0.7)
					(thickness 0.15)
				)
				(justify left bottom mirror)
			)
		)
		(fp_text user "Author: Antmicro"
			(at -0.95 -4.169 270)
			(layer "B.Fab")
			(effects
				(font
					(size 0.7 0.7)
					(thickness 0.15)
				)
				(justify left bottom mirror)
			)
		)
		(pad "1" smd roundrect
			(at -0.48 0 90)
			(size 0.59 0.64)
			(layers "B.Cu" "B.Mask" "B.Paste")
			(roundrect_rratio 0.25)
			(net 406 "Net-(J3-LED_YG_Y-)")
			(pintype "passive")
		)
		(pad "2" smd roundrect
			(at 0.48 0 90)
			(size 0.59 0.64)
			(layers "B.Cu" "B.Mask" "B.Paste")
			(roundrect_rratio 0.25)
			(net 128 "/2xRJ45/~{P0_LINK_LESS_THAN_10G}")
			(pintype "passive")
		)
	)
	(footprint "antmicro-footprints:C_0402_1005Metric"
		(layer "B.Cu")
		(at 156.111866 85.165117 180)
		(descr "Capacitor SMD 0402")
		(tags "capacitor SMD 0402")
		(property "Reference" "C196"
			(at -19.873134 -9.464883 0)
			(layer "B.SilkS")
			(effects
				(font
					(size 0.7 0.7)
					(thickness 0.15)
				)
				(justify mirror)
			)
		)
		(property "Value" "C_1u_25V_0402"
			(at -1.022927 -2.155213 0)
			(layer "B.Fab")
			(effects
				(font
					(size 0.7 0.7)
					(thickness 0.15)
				)
				(justify left bottom mirror)
			)
		)
		(property "Datasheet" "https://www.murata.com/products/productdetail?partno=GRM155R61E105KE11%23"
			(at 0 0 0)
			(layer "B.Fab")
			(hide yes)
			(effects
				(font
					(size 1.27 1.27)
					(thickness 0.15)
				)
				(justify mirror)
			)
		)
		(property "Description" "SMD Multilayer Ceramic Capacitor, 1 µF, 25 V, 0402 [1005 Metric], ± 10%, X5R, GRM Series"
			(at 0 0 0)
			(layer "B.Fab")
			(hide yes)
			(effects
				(font
					(size 1.27 1.27)
					(thickness 0.15)
				)
				(justify mirror)
			)
		)
		(property "MPN" "GRM155R61E105KE11J"
			(at 0 0 180)
			(unlocked yes)
			(layer "B.Fab")
			(hide yes)
			(effects
				(font
					(size 1 1)
					(thickness 0.15)
				)
				(justify mirror)
			)
		)
		(property "Manufacturer" "Murata"
			(at 0 0 180)
			(unlocked yes)
			(layer "B.Fab")
			(hide yes)
			(effects
				(font
					(size 1 1)
					(thickness 0.15)
				)
				(justify mirror)
			)
		)
		(property "License" "Apache-2.0"
			(at 0 0 180)
			(unlocked yes)
			(layer "B.Fab")
			(hide yes)
			(effects
				(font
					(size 1 1)
					(thickness 0.15)
				)
				(justify mirror)
			)
		)
		(property "Author" "Antmicro"
			(at 0 0 180)
			(unlocked yes)
			(layer "B.Fab")
			(hide yes)
			(effects
				(font
					(size 1 1)
					(thickness 0.15)
				)
				(justify mirror)
			)
		)
		(property "Val" "1u"
			(at 0 0 180)
			(unlocked yes)
			(layer "B.Fab")
			(hide yes)
			(effects
				(font
					(size 1 1)
					(thickness 0.15)
				)
				(justify mirror)
			)
		)
		(property "Voltage" "25V"
			(at 0 0 180)
			(unlocked yes)
			(layer "B.Fab")
			(hide yes)
			(effects
				(font
					(size 1 1)
					(thickness 0.15)
				)
				(justify mirror)
			)
		)
		(property "Dielectric" "X5R"
			(at 0 0 180)
			(unlocked yes)
			(layer "B.Fab")
			(hide yes)
			(effects
				(font
					(size 1 1)
					(thickness 0.15)
				)
				(justify mirror)
			)
		)
		(sheetname "/X710-AT2 power/")
		(sheetfile "x710-at2-power.kicad_sch")
		(attr smd)
		(fp_rect
			(start -0.925 0.47)
			(end 0.925 -0.47)
			(stroke
				(width 0.05)
				(type default)
			)
			(fill no)
			(layer "B.CrtYd")
		)
		(fp_line
			(start 0.504 0.25)
			(end 0.504 -0.248)
			(stroke
				(width 0.15)
				(type solid)
			)
			(layer "B.Fab")
		)
		(fp_line
			(start 0.504 -0.248)
			(end -0.494 -0.248)
			(stroke
				(width 0.15)
				(type solid)
			)
			(layer "B.Fab")
		)
		(fp_line
			(start -0.494 0.25)
			(end 0.504 0.25)
			(stroke
				(width 0.15)
				(type solid)
			)
			(layer "B.Fab")
		)
		(fp_line
			(start -0.494 -0.248)
			(end -0.494 0.25)
			(stroke
				(width 0.15)
				(type solid)
			)
			(layer "B.Fab")
		)
		(fp_text user "${REFERENCE}"
			(at -0.939 -4.599 0)
			(layer "B.Fab")
			(effects
				(font
					(size 0.7 0.7)
					(thickness 0.15)
				)
				(justify left bottom mirror)
			)
		)
		(fp_text user "Author: Antmicro"
			(at -0.939 -3.399 0)
			(layer "B.Fab")
			(effects
				(font
					(size 0.7 0.7)
					(thickness 0.15)
				)
				(justify left bottom mirror)
			)
		)
		(fp_text user "License: Apache-2.0"
			(at -0.939 -5.799 0)
			(layer "B.Fab")
			(effects
				(font
					(size 0.7 0.7)
					(thickness 0.15)
				)
				(justify left bottom mirror)
			)
		)
		(pad "1" smd roundrect
			(at -0.48 0 180)
			(size 0.59 0.64)
			(layers "B.Cu" "B.Mask" "B.Paste")
			(roundrect_rratio 0.25)
			(net 23 "GND")
			(pintype "passive")
		)
		(pad "2" smd roundrect
			(at 0.48 0 180)
			(size 0.59 0.64)
			(layers "B.Cu" "B.Mask" "B.Paste")
			(roundrect_rratio 0.25)
			(net 6 "DVDD")
			(pintype "passive")
		)
	)
)
